# T6G (Grand Teton) — schematic netlist excerpt (pin names and nets, part order shuffled) for the footprints in the layout excerpt that follows; sources: Cadence DE-HDL packaged netlist, KiCad conversion of 04192023_DAF0TMB3IC0_F0TG_MB_C_brd_V02_OCP.brd

C2487  Q_CAP  22UF 4V 20% X6S  pkg C0402  page 74 : A = PVDD11_S3_P1 ; B = GND
L28  Q_INDUCTOR  BLM15PD121SN1D/1300MA IND  pkg SMLF  page 290 : \1\ = P1V8_CPU0_RT_1D ; \2\ = P1V8_CPU0_RT1_1A_1D

(kicad_pcb
	(version 20260206)
	(generator "pcbnew")
	(generator_version "10.0")
	(general
		(thickness 1.6)
		(legacy_teardrops no)
	)
	(paper "A4")
	(title_block
		(title "04192023_DAF0TMB3IC0_F0TG_MB_C_brd_V02_OCP.brd")
		(comment 1 "Grand Teton / footprints 1670-1671 of 8354")
	)
	(layers
		(0 "F.Cu" signal "TOP")
		(4 "In1.Cu" signal "GND")
		(6 "In2.Cu" signal "IN1")
		(8 "In3.Cu" signal "GND1")
		(10 "In4.Cu" signal "IN2")
		(12 "In5.Cu" signal "GND2")
		(14 "In6.Cu" signal "IN3")
		(16 "In7.Cu" signal "GND3")
		(18 "In8.Cu" signal "VCC")
		(20 "In9.Cu" signal "VCC1")
		(22 "In10.Cu" signal "GND4")
		(24 "In11.Cu" signal "IN4")
		(26 "In12.Cu" signal "GND5")
		(28 "In13.Cu" signal "IN5")
		(30 "In14.Cu" signal "GND6")
		(32 "In15.Cu" signal "IN6")
		(34 "In16.Cu" signal "GND7")
		(2 "B.Cu" signal "BOTTOM")
		(9 "F.Adhes" user "F.Adhesive")
		(11 "B.Adhes" user "B.Adhesive")
		(13 "F.Paste" user "Package Geometry/Pastemask Top")
		(15 "B.Paste" user "Package Geometry/Pastemask Bottom")
		(5 "F.SilkS" user "Ref Des/Silkscreen Top")
		(7 "B.SilkS" user "Ref Des/Silkscreen Bottom")
		(1 "F.Mask" user "Board Geometry/Soldermask Top")
		(3 "B.Mask" user "Board Geometry/Soldermask Bottom")
		(17 "Dwgs.User" user "User.Drawings")
		(19 "Cmts.User" user "User.Comments")
		(21 "Eco1.User" user "User.Eco1")
		(23 "Eco2.User" user "User.Eco2")
		(25 "Edge.Cuts" user "Board Geometry/Outline")
		(27 "Margin" user)
		(31 "F.CrtYd" user "Package Geometry/Place Bound Top")
		(29 "B.CrtYd" user "Package Geometry/Place Bound Bottom")
		(35 "F.Fab" user "Ref Des/Assembly Top")
		(33 "B.Fab" user "Ref Des/Assembly Bottom")
	)
	(footprint ""
		(layer "F.Cu")
		(at 359.190036 -393.47648 180)
		(property "Reference" "L28"
			(at 0 0 180)
			(layer "F.SilkS")
			(hide yes)
			(effects
				(font
					(size 1.27 1.27)
				)
			)
		)
		(property "Value" ""
			(at 0 0 180)
			(layer "F.Fab")
			(effects
				(font
					(size 1.27 1.27)
				)
			)
		)
		(duplicate_pad_numbers_are_jumpers no)
		(fp_line
			(start 0.762 0.381)
			(end -0.762 0.381)
			(stroke
				(width 0.1524)
				(type default)
			)
			(layer "F.SilkS")
		)
		(fp_line
			(start 0.762 -0.381)
			(end 0.762 0.381)
			(stroke
				(width 0.1524)
				(type default)
			)
			(layer "F.SilkS")
		)
		(fp_line
			(start -0.762 0.381)
			(end -0.762 -0.381)
			(stroke
				(width 0.1524)
				(type default)
			)
			(layer "F.SilkS")
		)
		(fp_line
			(start -0.762 -0.381)
			(end 0.762 -0.381)
			(stroke
				(width 0.1524)
				(type default)
			)
			(layer "F.SilkS")
		)
		(fp_line
			(start 0.680466 0.306324)
			(end 0.118364 0.306324)
			(stroke
				(width 0.1)
				(type default)
			)
			(layer "F.Fab")
		)
		(fp_line
			(start 0.680466 -0.306324)
			(end 0.680466 0.306324)
			(stroke
				(width 0.1)
				(type default)
			)
			(layer "F.Fab")
		)
		(fp_line
			(start 0.118872 -0.2794)
			(end 0.118872 -0.306324)
			(stroke
				(width 0.1)
				(type default)
			)
			(layer "F.Fab")
		)
		(fp_line
			(start 0.118872 -0.306324)
			(end 0.680466 -0.306324)
			(stroke
				(width 0.1)
				(type default)
			)
			(layer "F.Fab")
		)
		(fp_line
			(start 0.118364 0.306324)
			(end 0.118364 0.2794)
			(stroke
				(width 0.1)
				(type default)
			)
			(layer "F.Fab")
		)
		(fp_line
			(start 0.118364 0.2794)
			(end -0.119634 0.2794)
			(stroke
				(width 0.1)
				(type default)
			)
			(layer "F.Fab")
		)
		(fp_line
			(start -0.118364 -0.2794)
			(end 0.118872 -0.2794)
			(stroke
				(width 0.1)
				(type default)
			)
			(layer "F.Fab")
		)
		(fp_line
			(start -0.118364 -0.307086)
			(end -0.118364 -0.2794)
			(stroke
				(width 0.1)
				(type default)
			)
			(layer "F.Fab")
		)
		(fp_line
			(start -0.119634 0.30607)
			(end -0.681736 0.30607)
			(stroke
				(width 0.1)
				(type default)
			)
			(layer "F.Fab")
		)
		(fp_line
			(start -0.119634 0.2794)
			(end -0.119634 0.30607)
			(stroke
				(width 0.1)
				(type default)
			)
			(layer "F.Fab")
		)
		(fp_line
			(start -0.681736 0.30607)
			(end -0.681736 -0.307086)
			(stroke
				(width 0.1)
				(type default)
			)
			(layer "F.Fab")
		)
		(fp_line
			(start -0.681736 -0.307086)
			(end -0.118364 -0.307086)
			(stroke
				(width 0.1)
				(type default)
			)
			(layer "F.Fab")
		)
		(pad "1" smd rect
			(at -0.40005 0)
			(size 0.4572 0.508)
			(layers "F.Cu" "F.Mask" "F.Paste")
			(net "P1V8_CPU0_RT_1D")
		)
		(pad "2" smd rect
			(at 0.40005 0)
			(size 0.4572 0.508)
			(layers "F.Cu" "F.Mask" "F.Paste")
			(net "P1V8_CPU0_RT1_1A_1D")
		)
	)
	(footprint ""
		(layer "F.Cu")
		(at 117.895624 -262.205216 180)
		(property "Reference" "C2487"
			(at 0 0 180)
			(layer "F.SilkS")
			(hide yes)
			(effects
				(font
					(size 1.27 1.27)
				)
			)
		)
		(property "Value" ""
			(at 0 0 180)
			(layer "F.Fab")
			(effects
				(font
					(size 1.27 1.27)
				)
			)
		)
		(duplicate_pad_numbers_are_jumpers no)
		(fp_line
			(start 0.7874 0.4064)
			(end -0.7874 0.4064)
			(stroke
				(width 0.1524)
				(type default)
			)
			(layer "F.SilkS")
		)
		(fp_line
			(start 0.7874 -0.4064)
			(end 0.7874 0.4064)
			(stroke
				(width 0.1524)
				(type default)
			)
			(layer "F.SilkS")
		)
		(fp_line
			(start -0.7874 0.4064)
			(end -0.7874 -0.4064)
			(stroke
				(width 0.1524)
				(type default)
			)
			(layer "F.SilkS")
		)
		(fp_line
			(start -0.7874 -0.4064)
			(end 0.7874 -0.4064)
			(stroke
				(width 0.1524)
				(type default)
			)
			(layer "F.SilkS")
		)
		(fp_line
			(start 0.67945 0.3048)
			(end 0.120396 0.3048)
			(stroke
				(width 0.1)
				(type default)
			)
			(layer "F.Fab")
		)
		(fp_line
			(start 0.67945 -0.3048)
			(end 0.67945 0.3048)
			(stroke
				(width 0.1)
				(type default)
			)
			(layer "F.Fab")
		)
		(fp_line
			(start 0.12065 -0.2794)
			(end 0.12065 -0.3048)
			(stroke
				(width 0.1)
				(type default)
			)
			(layer "F.Fab")
		)
		(fp_line
			(start 0.12065 -0.3048)
			(end 0.67945 -0.3048)
			(stroke
				(width 0.1)
				(type default)
			)
			(layer "F.Fab")
		)
		(fp_line
			(start 0.120396 0.3048)
			(end 0.120396 0.2794)
			(stroke
				(width 0.1)
				(type default)
			)
			(layer "F.Fab")
		)
		(fp_line
			(start 0.120396 0.2794)
			(end -0.12065 0.2794)
			(stroke
				(width 0.1)
				(type default)
			)
			(layer "F.Fab")
		)
		(fp_line
			(start -0.12065 0.3048)
			(end -0.67945 0.3048)
			(stroke
				(width 0.1)
				(type default)
			)
			(layer "F.Fab")
		)
		(fp_line
			(start -0.12065 0.2794)
			(end -0.12065 0.3048)
			(stroke
				(width 0.1)
				(type default)
			)
			(layer "F.Fab")
		)
		(fp_line
			(start -0.12065 -0.2794)
			(end 0.12065 -0.2794)
			(stroke
				(width 0.1)
				(type default)
			)
			(layer "F.Fab")
		)
		(fp_line
			(start -0.12065 -0.305054)
			(end -0.12065 -0.2794)
			(stroke
				(width 0.1)
				(type default)
			)
			(layer "F.Fab")
		)
		(fp_line
			(start -0.67945 0.3048)
			(end -0.67945 -0.305054)
			(stroke
				(width 0.1)
				(type default)
			)
			(layer "F.Fab")
		)
		(fp_line
			(start -0.67945 -0.305054)
			(end -0.12065 -0.305054)
			(stroke
				(width 0.1)
				(type default)
			)
			(layer "F.Fab")
		)
		(pad "1" smd circle
			(at -0.40005 0 180)
			(size 0 0)
			(layers "F.Cu" "F.Mask" "F.Paste")
			(net "PVDD11_S3_P1")
		)
		(pad "2" smd circle
			(at 0.40005 0 180)
			(size 0 0)
			(layers "F.Cu" "F.Mask" "F.Paste")
			(net "GND")
		)
	)
)
